# BASEBOARD_FAB2 (Tioga Pass) — schematic netlist excerpt (pin names and nets, part order shuffled) for the footprints in the layout excerpt that follows; sources: Cadence DE-HDL packaged netlist, KiCad conversion of Wiwynn_Tioga_Pass_MB.brd

C3M9  CAP  1.0UF 16V 10% X6S  pkg 0402  page 232 : A = VR_FET_SW_P12V_STBY_PVPP_DEF ; B = GND
C2N3  CAP_A  1.0UF 6.3V 10% X6S  pkg 0402V  page 132 : A = PVNN_PCH_STBY ; B = GND
C3N34  CAP  10UF 16V 10% X6S  pkg 0805  page 212 : A = VR_FET_SW_P12V_STBY_PVCCIO_CPU0 ; B = GND

(kicad_pcb
	(version 20260206)
	(generator "pcbnew")
	(generator_version "10.0")
	(general
		(thickness 1.6)
		(legacy_teardrops no)
	)
	(paper "A4")
	(title_block
		(title "Wiwynn_Tioga_Pass_MB.brd")
		(comment 1 "Tioga Pass / footprints 3001-3003 of 4770")
	)
	(layers
		(0 "F.Cu" signal "TOP")
		(4 "In1.Cu" signal "L2GND")
		(6 "In2.Cu" signal "L3")
		(8 "In3.Cu" signal "L4GND")
		(10 "In4.Cu" signal "L5")
		(12 "In5.Cu" signal "L6GND")
		(14 "In6.Cu" signal "L7VCC")
		(16 "In7.Cu" signal "L8VCC")
		(18 "In8.Cu" signal "L9GND")
		(20 "In9.Cu" signal "L10")
		(22 "In10.Cu" signal "L11GND")
		(24 "In11.Cu" signal "L12")
		(26 "In12.Cu" signal "L13GND")
		(2 "B.Cu" signal "BOTTOM")
		(9 "F.Adhes" user "F.Adhesive")
		(11 "B.Adhes" user "B.Adhesive")
		(13 "F.Paste" user "Package Geometry/Pastemask Top")
		(15 "B.Paste" user "Package Geometry/Pastemask Bottom")
		(5 "F.SilkS" user "Ref Des/Silkscreen Top")
		(7 "B.SilkS" user "Ref Des/Silkscreen Bottom")
		(1 "F.Mask" user "Board Geometry/Soldermask Top")
		(3 "B.Mask" user "Board Geometry/Soldermask Bottom")
		(17 "Dwgs.User" user "User.Drawings")
		(19 "Cmts.User" user "User.Comments")
		(21 "Eco1.User" user "User.Eco1")
		(23 "Eco2.User" user "User.Eco2")
		(25 "Edge.Cuts" user "Board Geometry/Outline")
		(27 "Margin" user)
		(31 "F.CrtYd" user "Package Geometry/Place Bound Top")
		(29 "B.CrtYd" user "Package Geometry/Place Bound Bottom")
		(35 "F.Fab" user "Ref Des/Assembly Top")
		(33 "B.Fab" user "Ref Des/Assembly Bottom")
	)
	(footprint ""
		(layer "B.Cu")
		(at 348.1578 -98.2218 -90)
		(property "Reference" "C3N34"
			(at 0 0 90)
			(layer "B.SilkS")
			(hide yes)
			(effects
				(font
					(size 1.27 1.27)
				)
				(justify mirror)
			)
		)
		(property "Value" ""
			(at 0 0 90)
			(layer "B.Fab")
			(effects
				(font
					(size 1.27 1.27)
				)
				(justify mirror)
			)
		)
		(duplicate_pad_numbers_are_jumpers no)
		(fp_poly
			(pts
				(xy 0.7239 -0.2159) (xy -0.7239 -0.2159) (xy -0.7239 1.9939) (xy 0.7239 1.9939)
			)
			(stroke
				(width 0)
				(type default)
			)
			(fill no)
			(layer "B.CrtYd")
		)
		(fp_line
			(start -0.7239 1.9939)
			(end -0.7239 -0.2159)
			(stroke
				(width 0.1)
				(type default)
			)
			(layer "B.Fab")
		)
		(fp_line
			(start 0.7239 1.9939)
			(end -0.7239 1.9939)
			(stroke
				(width 0.1)
				(type default)
			)
			(layer "B.Fab")
		)
		(fp_line
			(start -0.7239 -0.2159)
			(end 0.7239 -0.2159)
			(stroke
				(width 0.1)
				(type default)
			)
			(layer "B.Fab")
		)
		(fp_line
			(start 0.7239 -0.2159)
			(end 0.7239 1.9939)
			(stroke
				(width 0.1)
				(type default)
			)
			(layer "B.Fab")
		)
		(pad "1" smd rect
			(at 0 0 90)
			(size 1.27 1.016)
			(layers "B.Cu" "B.Mask" "B.Paste")
			(net "VR_FET_SW_P12V_STBY_PVCCIO_CPU0")
		)
		(pad "2" smd rect
			(at 0 1.778 90)
			(size 1.27 1.016)
			(layers "B.Cu" "B.Mask" "B.Paste")
			(net "GND")
		)
		(zone
			(layer "B.Cu")
			(hatch none 0.5)
			(connect_pads
				(clearance 0)
			)
			(min_thickness 0.25)
			(keepout
				(tracks not_allowed)
				(vias allowed)
				(pads allowed)
				(copperpour not_allowed)
				(footprints allowed)
			)
			(placement
				(enabled no)
				(sheetname "")
			)
			(fill
				(thermal_gap 0.5)
				(thermal_bridge_width 0.5)
				(island_removal_mode 0)
			)
			(polygon
				(pts
					(xy 347.6498 -97.5868) (xy 347.6498 -98.8568) (xy 346.8878 -98.8568) (xy 346.8878 -97.5868)
				)
			)
		)
	)
	(footprint ""
		(layer "B.Cu")
		(at 390.13765 -111.05515 180)
		(property "Reference" "C2N3"
			(at 0 0 0)
			(layer "B.SilkS")
			(hide yes)
			(effects
				(font
					(size 1.27 1.27)
				)
				(justify mirror)
			)
		)
		(property "Value" ""
			(at 0 0 0)
			(layer "B.Fab")
			(effects
				(font
					(size 1.27 1.27)
				)
				(justify mirror)
			)
		)
		(duplicate_pad_numbers_are_jumpers no)
		(fp_rect
			(start 0.2794 0.9144)
			(end -0.2794 -0.1143)
			(stroke
				(width 0)
				(type default)
			)
			(fill no)
			(layer "B.CrtYd")
		)
		(fp_line
			(start 0.2794 0.9144)
			(end 0.2794 -0.1143)
			(stroke
				(width 0.1)
				(type default)
			)
			(layer "B.Fab")
		)
		(fp_line
			(start 0.2794 -0.1143)
			(end -0.2794 -0.1143)
			(stroke
				(width 0.1)
				(type default)
			)
			(layer "B.Fab")
		)
		(fp_line
			(start -0.2794 0.9144)
			(end 0.2794 0.9144)
			(stroke
				(width 0.1)
				(type default)
			)
			(layer "B.Fab")
		)
		(fp_line
			(start -0.2794 -0.1143)
			(end -0.2794 0.9144)
			(stroke
				(width 0.1)
				(type default)
			)
			(layer "B.Fab")
		)
		(pad "1" smd custom
			(at 0 0 90)
			(size 0.10414 0.10414)
			(layers "B.Cu" "B.Mask" "B.Paste")
			(net "PVNN_PCH_STBY")
			(options
				(clearance outline)
				(anchor circle)
			)
			(primitives
				(gr_poly
					(pts
						(xy -0.20828 -0.08636) (xy -0.20828 0.08636) (xy -0.08636 0.20828) (xy 0.086614 0.20828) (xy 0.20828 0.086614)
						(xy 0.20828 -0.08636) (xy 0.08636 -0.20828) (xy -0.08636 -0.20828)
					)
					(width 0)
					(fill yes)
				)
			)
		)
		(pad "2" smd custom
			(at 0 0.8001 90)
			(size 0.10414 0.10414)
			(layers "B.Cu" "B.Mask" "B.Paste")
			(net "GND")
			(options
				(clearance outline)
				(anchor circle)
			)
			(primitives
				(gr_poly
					(pts
						(xy -0.20828 -0.08636) (xy -0.20828 0.08636) (xy -0.08636 0.20828) (xy 0.086614 0.20828) (xy 0.20828 0.086614)
						(xy 0.20828 -0.08636) (xy 0.08636 -0.20828) (xy -0.08636 -0.20828)
					)
					(width 0)
					(fill yes)
				)
			)
		)
		(zone
			(layer "B.Cu")
			(hatch none 0.5)
			(connect_pads
				(clearance 0)
			)
			(min_thickness 0.25)
			(keepout
				(tracks allowed)
				(vias not_allowed)
				(pads allowed)
				(copperpour not_allowed)
				(footprints allowed)
			)
			(placement
				(enabled no)
				(sheetname "")
			)
			(fill
				(thermal_gap 0.5)
				(thermal_bridge_width 0.5)
				(island_removal_mode 0)
			)
			(polygon
				(pts
					(xy 390.05002 -111.2647) (xy 390.05002 -111.6457) (xy 390.22528 -111.6457) (xy 390.225534 -111.2647)
				)
			)
		)
		(zone
			(layer "B.Cu")
			(hatch none 0.5)
			(connect_pads
				(clearance 0)
			)
			(min_thickness 0.25)
			(keepout
				(tracks not_allowed)
				(vias allowed)
				(pads allowed)
				(copperpour not_allowed)
				(footprints allowed)
			)
			(placement
				(enabled no)
				(sheetname "")
			)
			(fill
				(thermal_gap 0.5)
				(thermal_bridge_width 0.5)
				(island_removal_mode 0)
			)
			(polygon
				(pts
					(xy 390.05002 -111.2647) (xy 390.05002 -111.6457) (xy 390.22528 -111.6457) (xy 390.225534 -111.2647)
				)
			)
		)
	)
	(footprint ""
		(layer "B.Cu")
		(at 348.361 -133.604 180)
		(property "Reference" "C3M9"
			(at 0 0 0)
			(layer "B.SilkS")
			(hide yes)
			(effects
				(font
					(size 1.27 1.27)
				)
				(justify mirror)
			)
		)
		(property "Value" ""
			(at 0 0 0)
			(layer "B.Fab")
			(effects
				(font
					(size 1.27 1.27)
				)
				(justify mirror)
			)
		)
		(duplicate_pad_numbers_are_jumpers no)
		(fp_poly
			(pts
				(xy -0.3048 -0.1016) (xy -0.3048 0.9906) (xy 0.3048 0.9906) (xy 0.3048 -0.1016)
			)
			(stroke
				(width 0)
				(type default)
			)
			(fill no)
			(layer "B.CrtYd")
		)
		(fp_line
			(start 0.3048 0.9906)
			(end -0.3048 0.9906)
			(stroke
				(width 0.1)
				(type default)
			)
			(layer "B.Fab")
		)
		(fp_line
			(start 0.3048 -0.1016)
			(end 0.3048 0.9906)
			(stroke
				(width 0.1)
				(type default)
			)
			(layer "B.Fab")
		)
		(fp_line
			(start -0.3048 0.9906)
			(end -0.3048 -0.1016)
			(stroke
				(width 0.1)
				(type default)
			)
			(layer "B.Fab")
		)
		(fp_line
			(start -0.3048 -0.1016)
			(end 0.3048 -0.1016)
			(stroke
				(width 0.1)
				(type default)
			)
			(layer "B.Fab")
		)
		(pad "1" smd rect
			(at 0 0)
			(size 0.508 0.508)
			(layers "B.Cu" "B.Mask" "B.Paste")
			(net "VR_FET_SW_P12V_STBY_PVPP_DEF")
		)
		(pad "2" smd rect
			(at 0 0.889)
			(size 0.508 0.508)
			(layers "B.Cu" "B.Mask" "B.Paste")
			(net "GND")
		)
		(zone
			(layer "B.Cu")
			(hatch none 0.5)
			(connect_pads
				(clearance 0)
			)
			(min_thickness 0.25)
			(keepout
				(tracks not_allowed)
				(vias allowed)
				(pads allowed)
				(copperpour not_allowed)
				(footprints allowed)
			)
			(placement
				(enabled no)
				(sheetname "")
			)
			(fill
				(thermal_gap 0.5)
				(thermal_bridge_width 0.5)
				(island_removal_mode 0)
			)
			(polygon
				(pts
					(xy 348.107 -134.239) (xy 348.615 -134.239) (xy 348.615 -133.858) (xy 348.107 -133.858)
				)
			)
		)
		(zone
			(layer "B.Cu")
			(hatch none 0.5)
			(connect_pads
				(clearance 0)
			)
			(min_thickness 0.25)
			(keepout
				(tracks allowed)
				(vias not_allowed)
				(pads allowed)
				(copperpour not_allowed)
				(footprints allowed)
			)
			(placement
				(enabled no)
				(sheetname "")
			)
			(fill
				(thermal_gap 0.5)
				(thermal_bridge_width 0.5)
				(island_removal_mode 0)
			)
			(polygon
				(pts
					(xy 348.107 -133.858) (xy 348.615 -133.858) (xy 348.615 -134.239) (xy 348.107 -134.239)
				)
			)
		)
	)
)
